# T6G (Grand Teton) — schematic netlist excerpt (pin names and nets, part order shuffled) for the footprints in the layout excerpt that follows; sources: Cadence DE-HDL packaged netlist, KiCad conversion of 04192023_DAF0TMB3IC0_F0TG_MB_C_brd_V02_OCP.brd

R89  Q_RES  1K 1% EMPTY  pkg 0402LF  page 86 : A = P3V3 ; B = PWRGD_CHA_CPU0_DIMM0
C6042  Q_CAP  22UF 6.3V 20% X6S  pkg C0603  page 177 : A = P3V3_AUX_CPU0_USB_AVDD33 ; B = GND
C34  Q_CAP  22UF 16V 20% X6S  pkg C0805  page 131 : A = P12V_OCP_SFF_R ; B = GND

(kicad_pcb
	(version 20260206)
	(generator "pcbnew")
	(generator_version "10.0")
	(general
		(thickness 1.6)
		(legacy_teardrops no)
	)
	(paper "A4")
	(title_block
		(title "04192023_DAF0TMB3IC0_F0TG_MB_C_brd_V02_OCP.brd")
		(comment 1 "Grand Teton / footprints 7681-7683 of 8354")
	)
	(layers
		(0 "F.Cu" signal "TOP")
		(4 "In1.Cu" signal "GND")
		(6 "In2.Cu" signal "IN1")
		(8 "In3.Cu" signal "GND1")
		(10 "In4.Cu" signal "IN2")
		(12 "In5.Cu" signal "GND2")
		(14 "In6.Cu" signal "IN3")
		(16 "In7.Cu" signal "GND3")
		(18 "In8.Cu" signal "VCC")
		(20 "In9.Cu" signal "VCC1")
		(22 "In10.Cu" signal "GND4")
		(24 "In11.Cu" signal "IN4")
		(26 "In12.Cu" signal "GND5")
		(28 "In13.Cu" signal "IN5")
		(30 "In14.Cu" signal "GND6")
		(32 "In15.Cu" signal "IN6")
		(34 "In16.Cu" signal "GND7")
		(2 "B.Cu" signal "BOTTOM")
		(9 "F.Adhes" user "F.Adhesive")
		(11 "B.Adhes" user "B.Adhesive")
		(13 "F.Paste" user "Package Geometry/Pastemask Top")
		(15 "B.Paste" user "Package Geometry/Pastemask Bottom")
		(5 "F.SilkS" user "Ref Des/Silkscreen Top")
		(7 "B.SilkS" user "Ref Des/Silkscreen Bottom")
		(1 "F.Mask" user "Board Geometry/Soldermask Top")
		(3 "B.Mask" user "Board Geometry/Soldermask Bottom")
		(17 "Dwgs.User" user "User.Drawings")
		(19 "Cmts.User" user "User.Comments")
		(21 "Eco1.User" user "User.Eco1")
		(23 "Eco2.User" user "User.Eco2")
		(25 "Edge.Cuts" user "Board Geometry/Outline")
		(27 "Margin" user)
		(31 "F.CrtYd" user "Package Geometry/Place Bound Top")
		(29 "B.CrtYd" user "Package Geometry/Place Bound Bottom")
		(35 "F.Fab" user "Ref Des/Assembly Top")
		(33 "B.Fab" user "Ref Des/Assembly Bottom")
	)
	(footprint ""
		(layer "B.Cu")
		(at 304.023776 -193.99631)
		(property "Reference" "R89"
			(at 0 0 0)
			(layer "B.SilkS")
			(hide yes)
			(effects
				(font
					(size 1.27 1.27)
				)
				(justify mirror)
			)
		)
		(property "Value" ""
			(at 0 0 0)
			(layer "B.Fab")
			(effects
				(font
					(size 1.27 1.27)
				)
				(justify mirror)
			)
		)
		(duplicate_pad_numbers_are_jumpers no)
		(fp_line
			(start -0.7874 -0.4064)
			(end -0.7874 0.4064)
			(stroke
				(width 0.1524)
				(type default)
			)
			(layer "B.SilkS")
		)
		(fp_line
			(start -0.7874 0.4064)
			(end 0.7874 0.4064)
			(stroke
				(width 0.1524)
				(type default)
			)
			(layer "B.SilkS")
		)
		(fp_line
			(start 0.7874 -0.4064)
			(end -0.7874 -0.4064)
			(stroke
				(width 0.1524)
				(type default)
			)
			(layer "B.SilkS")
		)
		(fp_line
			(start 0.7874 0.4064)
			(end 0.7874 -0.4064)
			(stroke
				(width 0.1524)
				(type default)
			)
			(layer "B.SilkS")
		)
		(fp_line
			(start -0.67945 -0.3048)
			(end -0.67945 0.3048)
			(stroke
				(width 0.1)
				(type default)
			)
			(layer "B.Fab")
		)
		(fp_line
			(start -0.67945 0.3048)
			(end -0.120396 0.3048)
			(stroke
				(width 0.1)
				(type default)
			)
			(layer "B.Fab")
		)
		(fp_line
			(start -0.12065 -0.3048)
			(end -0.67945 -0.3048)
			(stroke
				(width 0.1)
				(type default)
			)
			(layer "B.Fab")
		)
		(fp_line
			(start -0.12065 -0.2794)
			(end -0.12065 -0.3048)
			(stroke
				(width 0.1)
				(type default)
			)
			(layer "B.Fab")
		)
		(fp_line
			(start -0.120396 0.2794)
			(end 0.12065 0.2794)
			(stroke
				(width 0.1)
				(type default)
			)
			(layer "B.Fab")
		)
		(fp_line
			(start -0.120396 0.3048)
			(end -0.120396 0.2794)
			(stroke
				(width 0.1)
				(type default)
			)
			(layer "B.Fab")
		)
		(fp_line
			(start 0.12065 -0.305054)
			(end 0.12065 -0.2794)
			(stroke
				(width 0.1)
				(type default)
			)
			(layer "B.Fab")
		)
		(fp_line
			(start 0.12065 -0.2794)
			(end -0.12065 -0.2794)
			(stroke
				(width 0.1)
				(type default)
			)
			(layer "B.Fab")
		)
		(fp_line
			(start 0.12065 0.2794)
			(end 0.12065 0.3048)
			(stroke
				(width 0.1)
				(type default)
			)
			(layer "B.Fab")
		)
		(fp_line
			(start 0.12065 0.3048)
			(end 0.67945 0.3048)
			(stroke
				(width 0.1)
				(type default)
			)
			(layer "B.Fab")
		)
		(fp_line
			(start 0.67945 -0.305054)
			(end 0.12065 -0.305054)
			(stroke
				(width 0.1)
				(type default)
			)
			(layer "B.Fab")
		)
		(fp_line
			(start 0.67945 0.3048)
			(end 0.67945 -0.305054)
			(stroke
				(width 0.1)
				(type default)
			)
			(layer "B.Fab")
		)
		(pad "1" smd circle
			(at 0.40005 0 180)
			(size 0 0)
			(layers "B.Cu" "B.Mask" "B.Paste")
			(net "P3V3")
		)
		(pad "2" smd circle
			(at -0.40005 0 180)
			(size 0 0)
			(layers "B.Cu" "B.Mask" "B.Paste")
			(net "PWRGD_CHA_CPU0_DIMM0")
		)
	)
	(footprint ""
		(layer "B.Cu")
		(at 440.333384 -16.014954)
		(property "Reference" "C34"
			(at 0 0 0)
			(layer "B.SilkS")
			(hide yes)
			(effects
				(font
					(size 1.27 1.27)
				)
				(justify mirror)
			)
		)
		(property "Value" ""
			(at 0 0 0)
			(layer "B.Fab")
			(effects
				(font
					(size 1.27 1.27)
				)
				(justify mirror)
			)
		)
		(duplicate_pad_numbers_are_jumpers no)
		(fp_line
			(start -1.524 -0.762)
			(end -1.524 0.762)
			(stroke
				(width 0.1524)
				(type default)
			)
			(layer "B.SilkS")
		)
		(fp_line
			(start -1.524 0.762)
			(end 1.524 0.762)
			(stroke
				(width 0.1524)
				(type default)
			)
			(layer "B.SilkS")
		)
		(fp_line
			(start 1.524 -0.762)
			(end -1.524 -0.762)
			(stroke
				(width 0.1524)
				(type default)
			)
			(layer "B.SilkS")
		)
		(fp_line
			(start 1.524 0.762)
			(end 1.524 -0.762)
			(stroke
				(width 0.1524)
				(type default)
			)
			(layer "B.SilkS")
		)
		(fp_line
			(start -1.1049 -0.724916)
			(end 1.1049 -0.724916)
			(stroke
				(width 0.1)
				(type default)
			)
			(layer "B.Fab")
		)
		(fp_line
			(start -1.1049 0.724916)
			(end -1.1049 -0.724916)
			(stroke
				(width 0.1)
				(type default)
			)
			(layer "B.Fab")
		)
		(fp_line
			(start 1.1049 -0.724916)
			(end 1.1049 0.724916)
			(stroke
				(width 0.1)
				(type default)
			)
			(layer "B.Fab")
		)
		(fp_line
			(start 1.1049 0.724916)
			(end -1.1049 0.724916)
			(stroke
				(width 0.1)
				(type default)
			)
			(layer "B.Fab")
		)
		(pad "1" smd rect
			(at 0.889 0)
			(size 1.016 1.27)
			(layers "B.Cu" "B.Mask" "B.Paste")
			(net "P12V_OCP_SFF_R")
		)
		(pad "2" smd rect
			(at -0.889 0)
			(size 1.016 1.27)
			(layers "B.Cu" "B.Mask" "B.Paste")
			(net "GND")
		)
	)
	(footprint ""
		(layer "B.Cu")
		(at 140.55852 -35.812222 -90)
		(property "Reference" "C6042"
			(at 0 0 90)
			(layer "B.SilkS")
			(hide yes)
			(effects
				(font
					(size 1.27 1.27)
				)
				(justify mirror)
			)
		)
		(property "Value" ""
			(at 0 0 90)
			(layer "B.Fab")
			(effects
				(font
					(size 1.27 1.27)
				)
				(justify mirror)
			)
		)
		(duplicate_pad_numbers_are_jumpers no)
		(fp_line
			(start -1.2954 0.5842)
			(end 1.2954 0.5842)
			(stroke
				(width 0.1524)
				(type default)
			)
			(layer "B.SilkS")
		)
		(fp_line
			(start 1.2954 0.5842)
			(end 1.2954 -0.5842)
			(stroke
				(width 0.1524)
				(type default)
			)
			(layer "B.SilkS")
		)
		(fp_line
			(start -1.2954 -0.5842)
			(end -1.2954 0.5842)
			(stroke
				(width 0.1524)
				(type default)
			)
			(layer "B.SilkS")
		)
		(fp_line
			(start 1.2954 -0.5842)
			(end -1.2954 -0.5842)
			(stroke
				(width 0.1524)
				(type default)
			)
			(layer "B.SilkS")
		)
		(fp_line
			(start -0.8636 0.4572)
			(end 0.8636 0.4572)
			(stroke
				(width 0.1)
				(type default)
			)
			(layer "B.Fab")
		)
		(fp_line
			(start 0.8636 0.4572)
			(end 0.8636 0.4064)
			(stroke
				(width 0.1)
				(type default)
			)
			(layer "B.Fab")
		)
		(fp_line
			(start -1.1938 0.4064)
			(end -0.8636 0.4064)
			(stroke
				(width 0.1)
				(type default)
			)
			(layer "B.Fab")
		)
		(fp_line
			(start -0.8636 0.4064)
			(end -0.8636 0.4572)
			(stroke
				(width 0.1)
				(type default)
			)
			(layer "B.Fab")
		)
		(fp_line
			(start 0.8636 0.4064)
			(end 1.1938 0.4064)
			(stroke
				(width 0.1)
				(type default)
			)
			(layer "B.Fab")
		)
		(fp_line
			(start 1.1938 0.4064)
			(end 1.1938 -0.4064)
			(stroke
				(width 0.1)
				(type default)
			)
			(layer "B.Fab")
		)
		(fp_line
			(start -1.1938 -0.4064)
			(end -1.1938 0.4064)
			(stroke
				(width 0.1)
				(type default)
			)
			(layer "B.Fab")
		)
		(fp_line
			(start -0.8636 -0.4064)
			(end -1.1938 -0.4064)
			(stroke
				(width 0.1)
				(type default)
			)
			(layer "B.Fab")
		)
		(fp_line
			(start 0.8636 -0.4064)
			(end 0.8636 -0.4572)
			(stroke
				(width 0.1)
				(type default)
			)
			(layer "B.Fab")
		)
		(fp_line
			(start 1.1938 -0.4064)
			(end 0.8636 -0.4064)
			(stroke
				(width 0.1)
				(type default)
			)
			(layer "B.Fab")
		)
		(fp_line
			(start -0.8636 -0.4572)
			(end -0.8636 -0.4064)
			(stroke
				(width 0.1)
				(type default)
			)
			(layer "B.Fab")
		)
		(fp_line
			(start 0.8636 -0.4572)
			(end -0.8636 -0.4572)
			(stroke
				(width 0.1)
				(type default)
			)
			(layer "B.Fab")
		)
		(pad "1" smd rect
			(at 0.7366 0 180)
			(size 0.7112 0.8128)
			(layers "B.Cu" "B.Mask" "B.Paste")
			(net "P3V3_AUX_CPU0_USB_AVDD33")
		)
		(pad "2" smd rect
			(at -0.7366 0 180)
			(size 0.7112 0.8128)
			(layers "B.Cu" "B.Mask" "B.Paste")
			(net "GND")
		)
	)
)
